(kicad_pcb
	(version 20260206)
	(generator "pcbnew")
	(generator_version "10.0")
	(general
		(thickness 1.6)
		(legacy_teardrops no)
	)
	(paper "A4")
	(title_block
		(title "Bryce Canyon_IOM_IOC_16318-2_OCP.brd")
		(comment 1 "Bryce Canyon / footprints 842-847 of 1605")
	)
	(layers
		(0 "F.Cu" signal "TOP")
		(4 "In1.Cu" signal "L2GND")
		(6 "In2.Cu" signal "L3")
		(8 "In3.Cu" signal "L4VCC")
		(10 "In4.Cu" signal "L5VCC")
		(12 "In5.Cu" signal "L6")
		(14 "In6.Cu" signal "L7GND")
		(2 "B.Cu" signal "BOTTOM")
		(9 "F.Adhes" user "F.Adhesive")
		(11 "B.Adhes" user "B.Adhesive")
		(13 "F.Paste" user "Package Geometry/Pastemask Top")
		(15 "B.Paste" user "Package Geometry/Pastemask Bottom")
		(5 "F.SilkS" user "Ref Des/Silkscreen Top")
		(7 "B.SilkS" user "Ref Des/Silkscreen Bottom")
		(1 "F.Mask" user "Board Geometry/Soldermask Top")
		(3 "B.Mask" user "Board Geometry/Soldermask Bottom")
		(17 "Dwgs.User" user "User.Drawings")
		(19 "Cmts.User" user "User.Comments")
		(21 "Eco1.User" user "User.Eco1")
		(23 "Eco2.User" user "User.Eco2")
		(25 "Edge.Cuts" user "Board Geometry/Outline")
		(27 "Margin" user)
		(31 "F.CrtYd" user "Package Geometry/Place Bound Top")
		(29 "B.CrtYd" user "Package Geometry/Place Bound Bottom")
		(35 "F.Fab" user "Ref Des/Assembly Top")
		(33 "B.Fab" user "Ref Des/Assembly Bottom")
	)
	(footprint ""
		(layer "F.Cu")
		(at 177.3682 -62.1792 90)
		(property "Reference" "R624"
			(at 0 0 90)
			(layer "F.SilkS")
			(hide yes)
			(effects
				(font
					(size 1.27 1.27)
				)
			)
		)
		(property "Value" "10KR2F-2-GP"
			(at 0.064008 -3.993896 90)
			(unlocked yes)
			(layer "F.Fab")
			(hide yes)
			(effects
				(font
					(size 1.016 1.016)
					(thickness 0.1524)
				)
			)
		)
		(property "Device Type" "R402H16"
			(at 0.064008 -5.517896 90)
			(unlocked yes)
			(layer "F.Fab")
			(hide yes)
			(effects
				(font
					(size 1.016 1.016)
					(thickness 0.1524)
				)
			)
		)
		(duplicate_pad_numbers_are_jumpers no)
		(fp_line
			(start 0.508 -0.9398)
			(end -0.508 -0.9398)
			(stroke
				(width 0.1524)
				(type default)
			)
			(layer "F.SilkS")
		)
		(fp_line
			(start -0.508 -0.9398)
			(end -0.508 0.9398)
			(stroke
				(width 0.1524)
				(type default)
			)
			(layer "F.SilkS")
		)
		(fp_rect
			(start -0.508 0.9398)
			(end 0.508 -0.9398)
			(stroke
				(width 0)
				(type default)
			)
			(fill no)
			(layer "F.CrtYd")
		)
		(fp_rect
			(start -0.508 0.9398)
			(end 0.508 -0.9398)
			(stroke
				(width 0)
				(type default)
			)
			(fill no)
			(layer "F.Fab")
		)
		(pad "1" smd custom
			(at 0 -0.4445 90)
			(size 0.1397 0.1397)
			(layers "F.Cu" "F.Mask" "F.Paste")
			(net "GND")
			(options
				(clearance outline)
				(anchor circle)
			)
			(primitives
				(gr_poly
					(pts
						(arc
							(start -0.1778 -0.2794)
							(mid -0.249642 -0.249642)
							(end -0.2794 -0.1778)
						)
						(arc
							(start -0.2794 0.1778)
							(mid -0.249642 0.249642)
							(end -0.1778 0.2794)
						)
						(arc
							(start 0.1778 0.2794)
							(mid 0.249642 0.249642)
							(end 0.2794 0.1778)
						)
						(arc
							(start 0.2794 -0.1778)
							(mid 0.249642 -0.249642)
							(end 0.1778 -0.2794)
						)
					)
					(width 0)
					(fill yes)
				)
			)
		)
		(pad "2" smd custom
			(at 0 0.4445 90)
			(size 0.1397 0.1397)
			(layers "F.Cu" "F.Mask" "F.Paste")
			(net "MEM_CLK_SEL")
			(options
				(clearance outline)
				(anchor circle)
			)
			(primitives
				(gr_poly
					(pts
						(arc
							(start -0.1778 -0.2794)
							(mid -0.249642 -0.249642)
							(end -0.2794 -0.1778)
						)
						(arc
							(start -0.2794 0.1778)
							(mid -0.249642 0.249642)
							(end -0.1778 0.2794)
						)
						(arc
							(start 0.1778 0.2794)
							(mid 0.249642 0.249642)
							(end 0.2794 0.1778)
						)
						(arc
							(start 0.2794 -0.1778)
							(mid 0.249642 -0.249642)
							(end 0.1778 -0.2794)
						)
					)
					(width 0)
					(fill yes)
				)
			)
		)
	)
	(footprint ""
		(layer "F.Cu")
		(at 77.8002 -162.2044 -90)
		(property "Reference" "PU11"
			(at 0 0 270)
			(layer "F.SilkS")
			(hide yes)
			(effects
				(font
					(size 1.27 1.27)
				)
			)
		)
		(property "Value" "TPS74801RGW-GP"
			(at -4.7244 -6.223 270)
			(unlocked yes)
			(layer "F.Fab")
			(hide yes)
			(effects
				(font
					(size 1.016 1.016)
					(thickness 0.1524)
				)
			)
		)
		(property "Device Type" "QFN20-1G3D15H40"
			(at -4.7244 -7.747 270)
			(unlocked yes)
			(layer "F.Fab")
			(hide yes)
			(effects
				(font
					(size 1.016 1.016)
					(thickness 0.1524)
				)
			)
		)
		(duplicate_pad_numbers_are_jumpers no)
		(fp_line
			(start -3.5179 3.5179)
			(end -2.2479 3.5179)
			(stroke
				(width 0.1524)
				(type default)
			)
			(layer "F.SilkS")
		)
		(fp_line
			(start 2.2479 3.5179)
			(end 3.5179 3.5179)
			(stroke
				(width 0.1524)
				(type default)
			)
			(layer "F.SilkS")
		)
		(fp_line
			(start 3.5179 3.5179)
			(end 3.5179 2.2479)
			(stroke
				(width 0.1524)
				(type default)
			)
			(layer "F.SilkS")
		)
		(fp_line
			(start 1.299972 3.160522)
			(end 1.299972 3.668522)
			(stroke
				(width 0.1524)
				(type default)
			)
			(layer "F.SilkS")
		)
		(fp_line
			(start -3.5179 2.2479)
			(end -3.5179 3.5179)
			(stroke
				(width 0.1524)
				(type default)
			)
			(layer "F.SilkS")
		)
		(fp_line
			(start -3.160522 1.299972)
			(end -3.922522 1.299972)
			(stroke
				(width 0.1524)
				(type default)
			)
			(layer "F.SilkS")
		)
		(fp_line
			(start 3.160522 -1.299972)
			(end 3.922522 -1.299972)
			(stroke
				(width 0.1524)
				(type default)
			)
			(layer "F.SilkS")
		)
		(fp_line
			(start -1.299972 -3.160522)
			(end -1.299972 -3.668522)
			(stroke
				(width 0.1524)
				(type default)
			)
			(layer "F.SilkS")
		)
		(fp_line
			(start -3.5179 -3.5179)
			(end -3.5179 -2.2479)
			(stroke
				(width 0.1524)
				(type default)
			)
			(layer "F.SilkS")
		)
		(fp_line
			(start -2.2479 -3.5179)
			(end -3.5179 -3.5179)
			(stroke
				(width 0.1524)
				(type default)
			)
			(layer "F.SilkS")
		)
		(fp_poly
			(pts
				(xy 3.5179 -3.5179) (xy 2.2479 -3.5179) (xy 3.5179 -2.2479)
			)
			(stroke
				(width 0)
				(type default)
			)
			(fill yes)
			(layer "F.SilkS")
		)
		(fp_rect
			(start -2.5019 2.5019)
			(end 2.5019 -2.5019)
			(stroke
				(width 0)
				(type default)
			)
			(fill no)
			(layer "F.CrtYd")
		)
		(fp_poly
			(pts
				(xy -3.5179 3.5179) (xy -3.5179 -3.5179) (xy 3.5179 -3.5179) (xy 3.5179 -2.5019) (xy -2.5019 -2.5019)
				(xy -2.5019 2.5019) (xy 2.5019 2.5019) (xy 2.5019 -2.49682) (xy 3.5179 -2.49682) (xy 3.5179 3.5179)
			)
			(stroke
				(width 0)
				(type default)
			)
			(fill no)
			(layer "F.CrtYd")
		)
		(fp_rect
			(start -3.5179 3.5179)
			(end 3.5179 -3.5179)
			(stroke
				(width 0)
				(type default)
			)
			(fill no)
			(layer "F.Fab")
		)
		(pad "1" smd rect
			(at 1.299972 -2.474722 270)
			(size 0.3556 1.0668)
			(layers "F.Cu" "F.Mask" "F.Paste")
			(net "TPS74801_P1V15_STBY_OUT")
		)
		(pad "2" smd rect
			(at 0.649986 -2.474722 270)
			(size 0.3556 1.0668)
			(layers "F.Cu" "F.Mask" "F.Paste")
			(net "GND")
		)
		(pad "3" smd rect
			(at 0 -2.474722 270)
			(size 0.3556 1.0668)
			(layers "F.Cu" "F.Mask" "F.Paste")
			(net "GND")
		)
		(pad "4" smd rect
			(at -0.649986 -2.474722 270)
			(size 0.3556 1.0668)
			(layers "F.Cu" "F.Mask" "F.Paste")
			(net "GND")
		)
		(pad "5" smd rect
			(at -1.299972 -2.474722 270)
			(size 0.3556 1.0668)
			(layers "F.Cu" "F.Mask" "F.Paste")
			(net "P1V8_STBY")
		)
		(pad "6" smd rect
			(at -2.474722 -1.299972 270)
			(size 1.0668 0.3556)
			(layers "F.Cu" "F.Mask" "F.Paste")
			(net "P1V8_STBY")
		)
		(pad "7" smd rect
			(at -2.474722 -0.649986 270)
			(size 1.0668 0.3556)
			(layers "F.Cu" "F.Mask" "F.Paste")
			(net "P1V8_STBY")
		)
		(pad "8" smd rect
			(at -2.474722 0 270)
			(size 1.0668 0.3556)
			(layers "F.Cu" "F.Mask" "F.Paste")
			(net "P1V8_STBY")
		)
		(pad "9" smd rect
			(at -2.474722 0.649986 270)
			(size 1.0668 0.3556)
			(layers "F.Cu" "F.Mask" "F.Paste")
			(net "P1V15_STBY_PG")
		)
		(pad "10" smd rect
			(at -2.474722 1.299972 270)
			(size 1.0668 0.3556)
			(layers "F.Cu" "F.Mask" "F.Paste")
			(net "TPS74801_P1V15_STBY_BIAS")
		)
		(pad "11" smd rect
			(at -1.299972 2.474722 270)
			(size 0.3556 1.0668)
			(layers "F.Cu" "F.Mask" "F.Paste")
			(net "TPS74801_P1V15_STBY_EN")
		)
		(pad "12" smd rect
			(at -0.649986 2.474722 270)
			(size 0.3556 1.0668)
			(layers "F.Cu" "F.Mask" "F.Paste")
			(net "GND")
		)
		(pad "13" smd rect
			(at 0 2.474722 270)
			(size 0.3556 1.0668)
			(layers "F.Cu" "F.Mask" "F.Paste")
			(net "GND")
		)
		(pad "14" smd rect
			(at 0.649986 2.474722 270)
			(size 0.3556 1.0668)
			(layers "F.Cu" "F.Mask" "F.Paste")
			(net "GND")
		)
		(pad "15" smd rect
			(at 1.299972 2.474722 270)
			(size 0.3556 1.0668)
			(layers "F.Cu" "F.Mask" "F.Paste")
			(net "TPS74801_P1V15_STBY_SS")
		)
		(pad "16" smd rect
			(at 2.474722 1.299972 270)
			(size 1.0668 0.3556)
			(layers "F.Cu" "F.Mask" "F.Paste")
			(net "TPS74801_P1V15_STBY_FB")
		)
		(pad "17" smd rect
			(at 2.474722 0.649986 270)
			(size 1.0668 0.3556)
			(layers "F.Cu" "F.Mask" "F.Paste")
			(net "GND")
		)
		(pad "18" smd rect
			(at 2.474722 0 270)
			(size 1.0668 0.3556)
			(layers "F.Cu" "F.Mask" "F.Paste")
			(net "TPS74801_P1V15_STBY_OUT")
		)
		(pad "19" smd rect
			(at 2.474722 -0.649986 270)
			(size 1.0668 0.3556)
			(layers "F.Cu" "F.Mask" "F.Paste")
			(net "TPS74801_P1V15_STBY_OUT")
		)
		(pad "20" smd rect
			(at 2.474722 -1.299972 270)
			(size 1.0668 0.3556)
			(layers "F.Cu" "F.Mask" "F.Paste")
			(net "TPS74801_P1V15_STBY_OUT")
		)
		(pad "21" smd rect
			(at 0 0 270)
			(size 3.2512 3.2512)
			(layers "F.Cu" "F.Mask" "F.Paste")
			(net "GND")
		)
	)
	(footprint ""
		(layer "F.Cu")
		(at 93.7006 -124.5362 180)
		(property "Reference" "U46"
			(at 0 0 180)
			(layer "F.SilkS")
			(hide yes)
			(effects
				(font
					(size 1.27 1.27)
				)
			)
		)
		(property "Value" "SN74LVC1G08DCKR-GP"
			(at -2.3368 -8.6868 180)
			(unlocked yes)
			(layer "F.Fab")
			(hide yes)
			(effects
				(font
					(size 1.016 1.016)
					(thickness 0.1524)
				)
			)
		)
		(property "Device Type" "SC70-5H44"
			(at -2.3114 -10.414 180)
			(unlocked yes)
			(layer "F.Fab")
			(hide yes)
			(effects
				(font
					(size 1.016 1.016)
					(thickness 0.1524)
				)
			)
		)
		(duplicate_pad_numbers_are_jumpers no)
		(fp_line
			(start 1.3843 -1.8034)
			(end 1.3843 -1.1176)
			(stroke
				(width 0.3302)
				(type default)
			)
			(layer "F.SilkS")
		)
		(fp_line
			(start 1.27 1.7018)
			(end -1.27 1.7018)
			(stroke
				(width 0.1524)
				(type default)
			)
			(layer "F.SilkS")
		)
		(fp_line
			(start 1.27 -1.7018)
			(end 1.27 1.7018)
			(stroke
				(width 0.1524)
				(type default)
			)
			(layer "F.SilkS")
		)
		(fp_line
			(start 0.6604 -1.8034)
			(end 1.3843 -1.8034)
			(stroke
				(width 0.3302)
				(type default)
			)
			(layer "F.SilkS")
		)
		(fp_line
			(start -1.27 1.7018)
			(end -1.27 -1.7018)
			(stroke
				(width 0.1524)
				(type default)
			)
			(layer "F.SilkS")
		)
		(fp_line
			(start -1.27 -1.7018)
			(end 1.27 -1.7018)
			(stroke
				(width 0.1524)
				(type default)
			)
			(layer "F.SilkS")
		)
		(fp_rect
			(start -1.524 1.9558)
			(end 1.524 -1.9558)
			(stroke
				(width 0)
				(type default)
			)
			(fill no)
			(layer "F.CrtYd")
		)
		(fp_poly
			(pts
				(xy -1.524 -1.9558) (xy 1.524 -1.9558) (xy 1.524 1.9558) (xy -1.524 1.9558)
			)
			(stroke
				(width 0)
				(type default)
			)
			(fill no)
			(layer "F.Fab")
		)
		(pad "1" smd rect
			(at 0.65024 -0.8255 180)
			(size 0.4064 1.2192)
			(layers "F.Cu" "F.Mask" "F.Paste")
			(net "UART_COMP_IN_R_RX")
		)
		(pad "2" smd rect
			(at 0 -0.8255 180)
			(size 0.4064 1.2192)
			(layers "F.Cu" "F.Mask" "F.Paste")
			(net "UART_BMC_COMP_IN_RX_R")
		)
		(pad "3" smd rect
			(at -0.65024 -0.8255 180)
			(size 0.4064 1.2192)
			(layers "F.Cu" "F.Mask" "F.Paste")
			(net "GND")
		)
		(pad "4" smd rect
			(at -0.65024 0.8255 180)
			(size 0.4064 1.2192)
			(layers "F.Cu" "F.Mask" "F.Paste")
			(net "UART_COMP_IN_RX_AND")
		)
		(pad "5" smd rect
			(at 0.65024 0.8255 180)
			(size 0.4064 1.2192)
			(layers "F.Cu" "F.Mask" "F.Paste")
			(net "P3V3_STBY")
		)
	)
	(footprint ""
		(layer "F.Cu")
		(at 177.2158 -128.016 90)
		(property "Reference" "R524"
			(at 0 0 90)
			(layer "F.SilkS")
			(hide yes)
			(effects
				(font
					(size 1.27 1.27)
				)
			)
		)
		(property "Value" "4K7R2F-GP"
			(at 0.064008 -3.993896 90)
			(unlocked yes)
			(layer "F.Fab")
			(hide yes)
			(effects
				(font
					(size 1.016 1.016)
					(thickness 0.1524)
				)
			)
		)
		(property "Device Type" "R402H16"
			(at 0.064008 -5.517896 90)
			(unlocked yes)
			(layer "F.Fab")
			(hide yes)
			(effects
				(font
					(size 1.016 1.016)
					(thickness 0.1524)
				)
			)
		)
		(duplicate_pad_numbers_are_jumpers no)
		(fp_line
			(start 0.508 -0.9398)
			(end -0.508 -0.9398)
			(stroke
				(width 0.1524)
				(type default)
			)
			(layer "F.SilkS")
		)
		(fp_line
			(start -0.508 -0.9398)
			(end -0.508 0.9398)
			(stroke
				(width 0.1524)
				(type default)
			)
			(layer "F.SilkS")
		)
		(fp_rect
			(start -0.508 0.9398)
			(end 0.508 -0.9398)
			(stroke
				(width 0)
				(type default)
			)
			(fill no)
			(layer "F.CrtYd")
		)
		(fp_rect
			(start -0.508 0.9398)
			(end 0.508 -0.9398)
			(stroke
				(width 0)
				(type default)
			)
			(fill no)
			(layer "F.Fab")
		)
		(pad "1" smd custom
			(at 0 -0.4445 90)
			(size 0.1397 0.1397)
			(layers "F.Cu" "F.Mask" "F.Paste")
			(net "P3V3")
			(options
				(clearance outline)
				(anchor circle)
			)
			(primitives
				(gr_poly
					(pts
						(arc
							(start -0.1778 -0.2794)
							(mid -0.249642 -0.249642)
							(end -0.2794 -0.1778)
						)
						(arc
							(start -0.2794 0.1778)
							(mid -0.249642 0.249642)
							(end -0.1778 0.2794)
						)
						(arc
							(start 0.1778 0.2794)
							(mid 0.249642 0.249642)
							(end 0.2794 0.1778)
						)
						(arc
							(start 0.2794 -0.1778)
							(mid 0.249642 -0.249642)
							(end 0.1778 -0.2794)
						)
					)
					(width 0)
					(fill yes)
				)
			)
		)
		(pad "2" smd custom
			(at 0 0.4445 90)
			(size 0.1397 0.1397)
			(layers "F.Cu" "F.Mask" "F.Paste")
			(net "P3V3_PG")
			(options
				(clearance outline)
				(anchor circle)
			)
			(primitives
				(gr_poly
					(pts
						(arc
							(start -0.1778 -0.2794)
							(mid -0.249642 -0.249642)
							(end -0.2794 -0.1778)
						)
						(arc
							(start -0.2794 0.1778)
							(mid -0.249642 0.249642)
							(end -0.1778 0.2794)
						)
						(arc
							(start 0.1778 0.2794)
							(mid 0.249642 0.249642)
							(end 0.2794 0.1778)
						)
						(arc
							(start 0.2794 -0.1778)
							(mid 0.249642 -0.249642)
							(end 0.1778 -0.2794)
						)
					)
					(width 0)
					(fill yes)
				)
			)
		)
	)
	(footprint ""
		(layer "F.Cu")
		(at 93.141546 -51.567334)
		(property "Reference" "C185"
			(at 0 0 0)
			(layer "F.SilkS")
			(hide yes)
			(effects
				(font
					(size 1.27 1.27)
				)
			)
		)
		(property "Value" "SCD1U16V2KX-3GP"
			(at 1.1811 -2.7051 0)
			(unlocked yes)
			(layer "F.Fab")
			(hide yes)
			(effects
				(font
					(size 1.016 1.016)
					(thickness 0.1524)
				)
			)
		)
		(property "Device Type" "C402H22"
			(at 1.1811 -4.2291 0)
			(unlocked yes)
			(layer "F.Fab")
			(hide yes)
			(effects
				(font
					(size 1.016 1.016)
					(thickness 0.1524)
				)
			)
		)
		(duplicate_pad_numbers_are_jumpers no)
		(fp_rect
			(start -0.4318 0.9525)
			(end 0.4318 -0.9525)
			(stroke
				(width 0)
				(type default)
			)
			(fill no)
			(layer "F.CrtYd")
		)
		(fp_rect
			(start -0.4318 0.9525)
			(end 0.4318 -0.9525)
			(stroke
				(width 0)
				(type default)
			)
			(fill no)
			(layer "F.Fab")
		)
		(pad "1" smd custom
			(at 0 -0.4445)
			(size 0.1524 0.1524)
			(layers "F.Cu" "F.Mask" "F.Paste")
			(net "P3V3_STBY")
			(options
				(clearance outline)
				(anchor circle)
			)
			(primitives
				(gr_poly
					(pts
						(arc
							(start 0.3048 -0.2032)
							(mid 0.275042 -0.275042)
							(end 0.2032 -0.3048)
						)
						(arc
							(start -0.2032 -0.3048)
							(mid -0.275042 -0.275042)
							(end -0.3048 -0.2032)
						)
						(arc
							(start -0.3048 0.2032)
							(mid -0.275042 0.275042)
							(end -0.2032 0.3048)
						)
						(arc
							(start 0.2032 0.3048)
							(mid 0.275042 0.275042)
							(end 0.3048 0.2032)
						)
					)
					(width 0)
					(fill yes)
				)
			)
		)
		(pad "2" smd custom
			(at 0 0.4445)
			(size 0.1524 0.1524)
			(layers "F.Cu" "F.Mask" "F.Paste")
			(net "GND")
			(options
				(clearance outline)
				(anchor circle)
			)
			(primitives
				(gr_poly
					(pts
						(arc
							(start 0.3048 -0.2032)
							(mid 0.275042 -0.275042)
							(end 0.2032 -0.3048)
						)
						(arc
							(start -0.2032 -0.3048)
							(mid -0.275042 -0.275042)
							(end -0.3048 -0.2032)
						)
						(arc
							(start -0.3048 0.2032)
							(mid -0.275042 0.275042)
							(end -0.2032 0.3048)
						)
						(arc
							(start 0.2032 0.3048)
							(mid 0.275042 0.275042)
							(end 0.3048 0.2032)
						)
					)
					(width 0)
					(fill yes)
				)
			)
		)
	)
	(footprint ""
		(layer "F.Cu")
		(at 44.2214 -159.7406)
		(property "Reference" "TP13"
			(at 0 0 0)
			(layer "F.SilkS")
			(hide yes)
			(effects
				(font
					(size 1.27 1.27)
				)
			)
		)
		(property "Value" "TPAD28-2-GP"
			(at -0.0127 -1.6637 0)
			(unlocked yes)
			(layer "F.Fab")
			(hide yes)
			(effects
				(font
					(size 1.016 1.016)
					(thickness 0.1524)
				)
			)
		)
		(property "Device Type" "TPAD28"
			(at -0.0127 -3.1877 0)
			(unlocked yes)
			(layer "F.Fab")
			(hide yes)
			(effects
				(font
					(size 1.016 1.016)
					(thickness 0.1524)
				)
			)
		)
		(duplicate_pad_numbers_are_jumpers no)
		(fp_poly
			(pts
				(arc
					(start 0.3556 0)
					(mid -0.3556 0)
					(end 0.3556 0)
				)
			)
			(stroke
				(width 0)
				(type default)
			)
			(fill no)
			(layer "F.CrtYd")
		)
		(fp_poly
			(pts
				(arc
					(start 0.6096 0)
					(mid -0.6096 0)
					(end 0.6096 0)
				)
			)
			(stroke
				(width 0)
				(type default)
			)
			(fill no)
			(layer "F.Fab")
		)
		(pad "1" smd circle
			(at 0 0)
			(size 0.7112 0.7112)
			(layers "F.Cu" "F.Mask" "F.Paste")
			(net "I2C_M2_1_SCL")
		)
	)
)
